FILE_TYPE = CONNECTIVITY;
{Allegro Design Entry HDL 17.4-2019 S026 (4007227) 1/17/2022}
"PAGE_NUMBER" = 4;
0"NC";
END.
